(kicad_pcb
	(version 20260206)
	(generator "pcbnew")
	(generator_version "10.0")
	(general
		(thickness 1.6)
		(legacy_teardrops no)
	)
	(paper "A4")
	(title_block
		(title "timecard-production-celestica-r4006 — R4006-B0001-02_R01.brd")
		(comment 1 "Time Appliance Project (Time Card) / footprints 1054-1058 of 1113")
	)
	(layers
		(0 "F.Cu" signal "TOP")
		(4 "In1.Cu" signal "L02_GND1")
		(6 "In2.Cu" signal "L03_SIG1")
		(8 "In3.Cu" signal "L04_GND2")
		(10 "In4.Cu" signal "L05_VCC1")
		(12 "In5.Cu" signal "L06_VCC2")
		(14 "In6.Cu" signal "L07_GND3")
		(16 "In7.Cu" signal "L08_SIG2")
		(18 "In8.Cu" signal "L09_GND4")
		(2 "B.Cu" signal "BOTTOM")
		(9 "F.Adhes" user "F.Adhesive")
		(11 "B.Adhes" user "B.Adhesive")
		(13 "F.Paste" user "Package Geometry/Pastemask Top")
		(15 "B.Paste" user "Package Geometry/Pastemask Bottom")
		(5 "F.SilkS" user "Ref Des/Silkscreen Top")
		(7 "B.SilkS" user "Ref Des/Silkscreen Bottom")
		(1 "F.Mask" user "Board Geometry/Soldermask Top")
		(3 "B.Mask" user "Board Geometry/Soldermask Bottom")
		(17 "Dwgs.User" user "User.Drawings")
		(19 "Cmts.User" user "User.Comments")
		(21 "Eco1.User" user "User.Eco1")
		(23 "Eco2.User" user "User.Eco2")
		(25 "Edge.Cuts" user "Board Geometry/Outline")
		(27 "Margin" user)
		(31 "F.CrtYd" user "Package Geometry/Place Bound Top")
		(29 "B.CrtYd" user "Package Geometry/Place Bound Bottom")
		(35 "F.Fab" user "Ref Des/Assembly Top")
		(33 "B.Fab" user "Ref Des/Assembly Bottom")
	)
	(footprint ""
		(layer "B.Cu")
		(at 85.471 -104.013)
		(property "Reference" "R37"
			(at 0 1.30937 0)
			(unlocked yes)
			(layer "B.SilkS")
			(effects
				(font
					(size 0.7874 0.5842)
					(thickness 0.1524)
				)
				(justify mirror)
			)
		)
		(property "Value" "VAL*"
			(at -0.02032 2.13233 0)
			(unlocked yes)
			(layer "B.Fab")
			(hide yes)
			(effects
				(font
					(size 0.7874 0.5842)
					(thickness 0.1524)
				)
				(justify mirror)
			)
		)
		(property "Tolerance" "TOL*"
			(at -0.044704 3.05435 0)
			(unlocked yes)
			(layer "Cmts.User")
			(hide yes)
			(effects
				(font
					(size 0.7874 0.5842)
					(thickness 0.1524)
				)
				(justify mirror)
			)
		)
		(property "User Part Number" "PARTNUM*"
			(at -0.02032 4.024884 0)
			(unlocked yes)
			(layer "Cmts.User")
			(hide yes)
			(effects
				(font
					(size 0.7874 0.5842)
					(thickness 0.1524)
				)
				(justify mirror)
			)
		)
		(property "Device Type" "RESISTOR-G155-100R0-J0,0OHM,-"
			(at -0.008382 1.210564 0)
			(unlocked yes)
			(layer "B.Fab")
			(hide yes)
			(effects
				(font
					(size 0.7874 0.5842)
					(thickness 0.1524)
				)
				(justify mirror)
			)
		)
		(duplicate_pad_numbers_are_jumpers no)
		(fp_line
			(start -1.143 -0.5588)
			(end 1.143 -0.5588)
			(stroke
				(width 0.1)
				(type default)
			)
			(layer "B.SilkS")
		)
		(fp_line
			(start -1.143 0.5588)
			(end -1.143 -0.5588)
			(stroke
				(width 0.1)
				(type default)
			)
			(layer "B.SilkS")
		)
		(fp_line
			(start 1.143 -0.5588)
			(end 1.143 0.5588)
			(stroke
				(width 0.1)
				(type default)
			)
			(layer "B.SilkS")
		)
		(fp_line
			(start 1.143 0.5588)
			(end -1.143 0.5588)
			(stroke
				(width 0.1)
				(type default)
			)
			(layer "B.SilkS")
		)
		(fp_poly
			(pts
				(xy 1.143 0.5588) (xy -1.143 0.5588) (xy -1.143 -0.5588) (xy 1.143 -0.5588)
			)
			(stroke
				(width 0)
				(type default)
			)
			(fill no)
			(layer "B.CrtYd")
		)
		(fp_line
			(start -0.508 -0.3048)
			(end 0.508 -0.3048)
			(stroke
				(width 0.1)
				(type default)
			)
			(layer "B.Fab")
		)
		(fp_line
			(start -0.508 0.3048)
			(end -0.508 -0.3048)
			(stroke
				(width 0.1)
				(type default)
			)
			(layer "B.Fab")
		)
		(fp_line
			(start 0.508 -0.3048)
			(end 0.508 0.3048)
			(stroke
				(width 0.1)
				(type default)
			)
			(layer "B.Fab")
		)
		(fp_line
			(start 0.508 0.3048)
			(end -0.508 0.3048)
			(stroke
				(width 0.1)
				(type default)
			)
			(layer "B.Fab")
		)
		(pad "1" smd rect
			(at 0.5334 0 180)
			(size 0.7112 0.6096)
			(layers "B.Cu" "B.Mask" "B.Paste")
			(net "XP3R3V_BT")
		)
		(pad "2" smd rect
			(at -0.5334 0 180)
			(size 0.7112 0.6096)
			(layers "B.Cu" "B.Mask" "B.Paste")
			(net "UNNAMED_517_CAPACITOR_I27_1")
		)
		(zone
			(layer "B.Cu")
			(hatch none 0.5)
			(connect_pads
				(clearance 0)
			)
			(min_thickness 0.25)
			(keepout
				(tracks allowed)
				(vias not_allowed)
				(pads allowed)
				(copperpour not_allowed)
				(footprints allowed)
			)
			(placement
				(enabled no)
				(sheetname "")
			)
			(fill
				(thermal_gap 0.5)
				(thermal_bridge_width 0.5)
				(island_removal_mode 0)
			)
			(polygon
				(pts
					(xy 85.5472 -103.7082) (xy 85.5472 -104.3178) (xy 85.3948 -104.3178) (xy 85.3948 -103.7082)
				)
			)
		)
		(zone
			(layer "B.Cu")
			(hatch none 0.5)
			(connect_pads
				(clearance 0)
			)
			(min_thickness 0.25)
			(keepout
				(tracks not_allowed)
				(vias allowed)
				(pads allowed)
				(copperpour not_allowed)
				(footprints allowed)
			)
			(placement
				(enabled no)
				(sheetname "")
			)
			(fill
				(thermal_gap 0.5)
				(thermal_bridge_width 0.5)
				(island_removal_mode 0)
			)
			(polygon
				(pts
					(xy 85.5472 -103.7082) (xy 85.5472 -104.3178) (xy 85.3948 -104.3178) (xy 85.3948 -103.7082)
				)
			)
		)
	)
	(footprint ""
		(layer "B.Cu")
		(at 111.125 -104.521)
		(property "Reference" "R322"
			(at 0.381 -3.00863 0)
			(unlocked yes)
			(layer "B.SilkS")
			(effects
				(font
					(size 0.7874 0.5842)
					(thickness 0.1524)
				)
				(justify mirror)
			)
		)
		(property "Value" "VAL*"
			(at -0.02032 2.13233 0)
			(unlocked yes)
			(layer "B.Fab")
			(hide yes)
			(effects
				(font
					(size 0.7874 0.5842)
					(thickness 0.1524)
				)
				(justify mirror)
			)
		)
		(property "Tolerance" "TOL*"
			(at -0.044704 3.05435 0)
			(unlocked yes)
			(layer "Cmts.User")
			(hide yes)
			(effects
				(font
					(size 0.7874 0.5842)
					(thickness 0.1524)
				)
				(justify mirror)
			)
		)
		(property "User Part Number" "PARTNUM*"
			(at -0.02032 4.024884 0)
			(unlocked yes)
			(layer "Cmts.User")
			(hide yes)
			(effects
				(font
					(size 0.7874 0.5842)
					(thickness 0.1524)
				)
				(justify mirror)
			)
		)
		(property "Device Type" "RESISTOR-G155-133R0-01,33OHM,1%"
			(at -0.008382 1.210564 0)
			(unlocked yes)
			(layer "B.Fab")
			(hide yes)
			(effects
				(font
					(size 0.7874 0.5842)
					(thickness 0.1524)
				)
				(justify mirror)
			)
		)
		(duplicate_pad_numbers_are_jumpers no)
		(fp_line
			(start -1.143 -0.5588)
			(end 1.143 -0.5588)
			(stroke
				(width 0.1)
				(type default)
			)
			(layer "B.SilkS")
		)
		(fp_line
			(start -1.143 0.5588)
			(end -1.143 -0.5588)
			(stroke
				(width 0.1)
				(type default)
			)
			(layer "B.SilkS")
		)
		(fp_line
			(start 1.143 -0.5588)
			(end 1.143 0.5588)
			(stroke
				(width 0.1)
				(type default)
			)
			(layer "B.SilkS")
		)
		(fp_line
			(start 1.143 0.5588)
			(end -1.143 0.5588)
			(stroke
				(width 0.1)
				(type default)
			)
			(layer "B.SilkS")
		)
		(fp_poly
			(pts
				(xy 1.143 0.5588) (xy -1.143 0.5588) (xy -1.143 -0.5588) (xy 1.143 -0.5588)
			)
			(stroke
				(width 0)
				(type default)
			)
			(fill no)
			(layer "B.CrtYd")
		)
		(fp_line
			(start -0.508 -0.3048)
			(end 0.508 -0.3048)
			(stroke
				(width 0.1)
				(type default)
			)
			(layer "B.Fab")
		)
		(fp_line
			(start -0.508 0.3048)
			(end -0.508 -0.3048)
			(stroke
				(width 0.1)
				(type default)
			)
			(layer "B.Fab")
		)
		(fp_line
			(start 0.508 -0.3048)
			(end 0.508 0.3048)
			(stroke
				(width 0.1)
				(type default)
			)
			(layer "B.Fab")
		)
		(fp_line
			(start 0.508 0.3048)
			(end -0.508 0.3048)
			(stroke
				(width 0.1)
				(type default)
			)
			(layer "B.Fab")
		)
		(pad "1" smd rect
			(at 0.5334 0 180)
			(size 0.7112 0.6096)
			(layers "B.Cu" "B.Mask" "B.Paste")
			(net "FPGA_M_RGB_LED_I2C_SCL")
		)
		(pad "2" smd rect
			(at -0.5334 0 180)
			(size 0.7112 0.6096)
			(layers "B.Cu" "B.Mask" "B.Paste")
			(net "R_RGB_LED_I2C_SCL")
		)
		(zone
			(layer "B.Cu")
			(hatch none 0.5)
			(connect_pads
				(clearance 0)
			)
			(min_thickness 0.25)
			(keepout
				(tracks not_allowed)
				(vias allowed)
				(pads allowed)
				(copperpour not_allowed)
				(footprints allowed)
			)
			(placement
				(enabled no)
				(sheetname "")
			)
			(fill
				(thermal_gap 0.5)
				(thermal_bridge_width 0.5)
				(island_removal_mode 0)
			)
			(polygon
				(pts
					(xy 111.2012 -104.2162) (xy 111.2012 -104.8258) (xy 111.0488 -104.8258) (xy 111.0488 -104.2162)
				)
			)
		)
		(zone
			(layer "B.Cu")
			(hatch none 0.5)
			(connect_pads
				(clearance 0)
			)
			(min_thickness 0.25)
			(keepout
				(tracks allowed)
				(vias not_allowed)
				(pads allowed)
				(copperpour not_allowed)
				(footprints allowed)
			)
			(placement
				(enabled no)
				(sheetname "")
			)
			(fill
				(thermal_gap 0.5)
				(thermal_bridge_width 0.5)
				(island_removal_mode 0)
			)
			(polygon
				(pts
					(xy 111.2012 -104.2162) (xy 111.2012 -104.8258) (xy 111.0488 -104.8258) (xy 111.0488 -104.2162)
				)
			)
		)
	)
	(footprint ""
		(layer "B.Cu")
		(at 44.323 -99.314 180)
		(property "Reference" "C44"
			(at -2.4384 -0.03937 0)
			(unlocked yes)
			(layer "B.SilkS")
			(effects
				(font
					(size 0.7874 0.5842)
					(thickness 0.1524)
				)
				(justify mirror)
			)
		)
		(property "Value" "VAL*"
			(at -0.0762 2.067306 180)
			(unlocked yes)
			(layer "B.Fab")
			(hide yes)
			(effects
				(font
					(size 0.7874 0.5842)
					(thickness 0.1524)
				)
				(justify mirror)
			)
		)
		(property "Tolerance" "TOL*"
			(at -0.0762 3.032506 180)
			(unlocked yes)
			(layer "Cmts.User")
			(hide yes)
			(effects
				(font
					(size 0.7874 0.5842)
					(thickness 0.1524)
				)
				(justify mirror)
			)
		)
		(property "User Part Number" "PARTNUM*"
			(at -0.1016 4.023106 180)
			(unlocked yes)
			(layer "Cmts.User")
			(hide yes)
			(effects
				(font
					(size 0.7874 0.5842)
					(thickness 0.1524)
				)
				(justify mirror)
			)
		)
		(property "Device Type" "CAPACITOR-G105-0B104-EK,0.1UF,A"
			(at -0.0508 1.127506 180)
			(unlocked yes)
			(layer "B.Fab")
			(hide yes)
			(effects
				(font
					(size 0.7874 0.5842)
					(thickness 0.1524)
				)
				(justify mirror)
			)
		)
		(duplicate_pad_numbers_are_jumpers no)
		(fp_line
			(start 1.143 0.5588)
			(end -1.143 0.5588)
			(stroke
				(width 0.1)
				(type default)
			)
			(layer "B.SilkS")
		)
		(fp_line
			(start 1.143 -0.5588)
			(end 1.143 0.5588)
			(stroke
				(width 0.1)
				(type default)
			)
			(layer "B.SilkS")
		)
		(fp_line
			(start -1.143 0.5588)
			(end -1.143 -0.5588)
			(stroke
				(width 0.1)
				(type default)
			)
			(layer "B.SilkS")
		)
		(fp_line
			(start -1.143 -0.5588)
			(end 1.143 -0.5588)
			(stroke
				(width 0.1)
				(type default)
			)
			(layer "B.SilkS")
		)
		(fp_rect
			(start 1.143 0.5588)
			(end -1.143 -0.5588)
			(stroke
				(width 0)
				(type default)
			)
			(fill no)
			(layer "B.CrtYd")
		)
		(fp_line
			(start 0.508 0.3048)
			(end -0.508 0.3048)
			(stroke
				(width 0.1)
				(type default)
			)
			(layer "B.Fab")
		)
		(fp_line
			(start 0.508 -0.3048)
			(end 0.508 0.3048)
			(stroke
				(width 0.1)
				(type default)
			)
			(layer "B.Fab")
		)
		(fp_line
			(start -0.508 0.3048)
			(end -0.508 -0.3048)
			(stroke
				(width 0.1)
				(type default)
			)
			(layer "B.Fab")
		)
		(fp_line
			(start -0.508 -0.3048)
			(end 0.508 -0.3048)
			(stroke
				(width 0.1)
				(type default)
			)
			(layer "B.Fab")
		)
		(pad "1" smd rect
			(at 0.5334 0)
			(size 0.7112 0.6096)
			(layers "B.Cu" "B.Mask" "B.Paste")
			(net "UNNAMED_516_CAPACITOR_I27_1")
		)
		(pad "2" smd rect
			(at -0.5334 0)
			(size 0.7112 0.6096)
			(layers "B.Cu" "B.Mask" "B.Paste")
			(net "XP5R0V_SW")
		)
		(zone
			(layer "B.Cu")
			(hatch none 0.5)
			(connect_pads
				(clearance 0)
			)
			(min_thickness 0.25)
			(keepout
				(tracks allowed)
				(vias not_allowed)
				(pads allowed)
				(copperpour not_allowed)
				(footprints allowed)
			)
			(placement
				(enabled no)
				(sheetname "")
			)
			(fill
				(thermal_gap 0.5)
				(thermal_bridge_width 0.5)
				(island_removal_mode 0)
			)
			(polygon
				(pts
					(xy 44.2468 -99.6188) (xy 44.2468 -99.0092) (xy 44.3992 -99.0092) (xy 44.3992 -99.6188)
				)
			)
		)
	)
	(footprint ""
		(layer "B.Cu")
		(at 156.718 -39.497 -90)
		(property "Reference" "R428"
			(at 6.77037 0.635 0)
			(unlocked yes)
			(layer "B.SilkS")
			(effects
				(font
					(size 0.7874 0.5842)
					(thickness 0.1524)
				)
				(justify mirror)
			)
		)
		(property "Value" "VAL*"
			(at -0.02032 2.13233 270)
			(unlocked yes)
			(layer "B.Fab")
			(hide yes)
			(effects
				(font
					(size 0.7874 0.5842)
					(thickness 0.1524)
				)
				(justify mirror)
			)
		)
		(property "Tolerance" "TOL*"
			(at -0.044704 3.05435 270)
			(unlocked yes)
			(layer "Cmts.User")
			(hide yes)
			(effects
				(font
					(size 0.7874 0.5842)
					(thickness 0.1524)
				)
				(justify mirror)
			)
		)
		(property "User Part Number" "PARTNUM*"
			(at -0.02032 4.024884 270)
			(unlocked yes)
			(layer "Cmts.User")
			(hide yes)
			(effects
				(font
					(size 0.7874 0.5842)
					(thickness 0.1524)
				)
				(justify mirror)
			)
		)
		(property "Device Type" "RESISTOR-G155-133R0-01,33OHM,1%"
			(at -0.008382 1.210564 270)
			(unlocked yes)
			(layer "B.Fab")
			(hide yes)
			(effects
				(font
					(size 0.7874 0.5842)
					(thickness 0.1524)
				)
				(justify mirror)
			)
		)
		(duplicate_pad_numbers_are_jumpers no)
		(fp_line
			(start -1.143 0.5588)
			(end -1.143 -0.5588)
			(stroke
				(width 0.1)
				(type default)
			)
			(layer "B.SilkS")
		)
		(fp_line
			(start 1.143 0.5588)
			(end -1.143 0.5588)
			(stroke
				(width 0.1)
				(type default)
			)
			(layer "B.SilkS")
		)
		(fp_line
			(start -1.143 -0.5588)
			(end 1.143 -0.5588)
			(stroke
				(width 0.1)
				(type default)
			)
			(layer "B.SilkS")
		)
		(fp_line
			(start 1.143 -0.5588)
			(end 1.143 0.5588)
			(stroke
				(width 0.1)
				(type default)
			)
			(layer "B.SilkS")
		)
		(fp_poly
			(pts
				(xy 1.143 0.5588) (xy -1.143 0.5588) (xy -1.143 -0.5588) (xy 1.143 -0.5588)
			)
			(stroke
				(width 0)
				(type default)
			)
			(fill no)
			(layer "B.CrtYd")
		)
		(fp_line
			(start -0.508 0.3048)
			(end -0.508 -0.3048)
			(stroke
				(width 0.1)
				(type default)
			)
			(layer "B.Fab")
		)
		(fp_line
			(start 0.508 0.3048)
			(end -0.508 0.3048)
			(stroke
				(width 0.1)
				(type default)
			)
			(layer "B.Fab")
		)
		(fp_line
			(start -0.508 -0.3048)
			(end 0.508 -0.3048)
			(stroke
				(width 0.1)
				(type default)
			)
			(layer "B.Fab")
		)
		(fp_line
			(start 0.508 -0.3048)
			(end 0.508 0.3048)
			(stroke
				(width 0.1)
				(type default)
			)
			(layer "B.Fab")
		)
		(pad "1" smd rect
			(at 0.5334 0 90)
			(size 0.7112 0.6096)
			(layers "B.Cu" "B.Mask" "B.Paste")
			(net "FPGA_IO_6")
		)
		(pad "2" smd rect
			(at -0.5334 0 90)
			(size 0.7112 0.6096)
			(layers "B.Cu" "B.Mask" "B.Paste")
			(net "UNNAMED_16_CONNHDR2X6FSSMT_I1_6")
		)
		(zone
			(layer "B.Cu")
			(hatch none 0.5)
			(connect_pads
				(clearance 0)
			)
			(min_thickness 0.25)
			(keepout
				(tracks not_allowed)
				(vias allowed)
				(pads allowed)
				(copperpour not_allowed)
				(footprints allowed)
			)
			(placement
				(enabled no)
				(sheetname "")
			)
			(fill
				(thermal_gap 0.5)
				(thermal_bridge_width 0.5)
				(island_removal_mode 0)
			)
			(polygon
				(pts
					(xy 156.4132 -39.4208) (xy 157.0228 -39.4208) (xy 157.0228 -39.5732) (xy 156.4132 -39.5732)
				)
			)
		)
		(zone
			(layer "B.Cu")
			(hatch none 0.5)
			(connect_pads
				(clearance 0)
			)
			(min_thickness 0.25)
			(keepout
				(tracks allowed)
				(vias not_allowed)
				(pads allowed)
				(copperpour not_allowed)
				(footprints allowed)
			)
			(placement
				(enabled no)
				(sheetname "")
			)
			(fill
				(thermal_gap 0.5)
				(thermal_bridge_width 0.5)
				(island_removal_mode 0)
			)
			(polygon
				(pts
					(xy 156.4132 -39.4208) (xy 157.0228 -39.4208) (xy 157.0228 -39.5732) (xy 156.4132 -39.5732)
				)
			)
		)
	)
	(footprint ""
		(layer "B.Cu")
		(at 138.4935 -67.5259 -90)
		(property "Reference" "R402"
			(at 0.8509 1.24587 270)
			(unlocked yes)
			(layer "B.SilkS")
			(effects
				(font
					(size 0.7874 0.5842)
					(thickness 0.1524)
				)
				(justify mirror)
			)
		)
		(property "Value" "VAL*"
			(at -0.02032 2.13233 270)
			(unlocked yes)
			(layer "B.Fab")
			(hide yes)
			(effects
				(font
					(size 0.7874 0.5842)
					(thickness 0.1524)
				)
				(justify mirror)
			)
		)
		(property "Device Type" "RESISTOR-G155-14701-01,4.7KOHMA"
			(at -0.008382 1.210564 270)
			(unlocked yes)
			(layer "B.Fab")
			(hide yes)
			(effects
				(font
					(size 0.7874 0.5842)
					(thickness 0.1524)
				)
				(justify mirror)
			)
		)
		(property "User Part Number" "PARTNUM*"
			(at -0.02032 4.024884 270)
			(unlocked yes)
			(layer "Cmts.User")
			(hide yes)
			(effects
				(font
					(size 0.7874 0.5842)
					(thickness 0.1524)
				)
				(justify mirror)
			)
		)
		(property "Tolerance" "TOL*"
			(at -0.044704 3.05435 270)
			(unlocked yes)
			(layer "Cmts.User")
			(hide yes)
			(effects
				(font
					(size 0.7874 0.5842)
					(thickness 0.1524)
				)
				(justify mirror)
			)
		)
		(duplicate_pad_numbers_are_jumpers no)
		(fp_line
			(start -1.143 0.5588)
			(end -1.143 -0.5588)
			(stroke
				(width 0.1)
				(type default)
			)
			(layer "B.SilkS")
		)
		(fp_line
			(start 1.143 0.5588)
			(end -1.143 0.5588)
			(stroke
				(width 0.1)
				(type default)
			)
			(layer "B.SilkS")
		)
		(fp_line
			(start -1.143 -0.5588)
			(end 1.143 -0.5588)
			(stroke
				(width 0.1)
				(type default)
			)
			(layer "B.SilkS")
		)
		(fp_line
			(start 1.143 -0.5588)
			(end 1.143 0.5588)
			(stroke
				(width 0.1)
				(type default)
			)
			(layer "B.SilkS")
		)
		(fp_rect
			(start 1.143 0.5588)
			(end -1.143 -0.5588)
			(stroke
				(width 0)
				(type default)
			)
			(fill no)
			(layer "B.CrtYd")
		)
		(fp_line
			(start -0.508 0.3048)
			(end -0.508 -0.3048)
			(stroke
				(width 0.1)
				(type default)
			)
			(layer "B.Fab")
		)
		(fp_line
			(start 0.508 0.3048)
			(end -0.508 0.3048)
			(stroke
				(width 0.1)
				(type default)
			)
			(layer "B.Fab")
		)
		(fp_line
			(start -0.508 -0.3048)
			(end 0.508 -0.3048)
			(stroke
				(width 0.1)
				(type default)
			)
			(layer "B.Fab")
		)
		(fp_line
			(start 0.508 -0.3048)
			(end 0.508 0.3048)
			(stroke
				(width 0.1)
				(type default)
			)
			(layer "B.Fab")
		)
		(pad "1" smd rect
			(at 0.5334 0 90)
			(size 0.7112 0.6096)
			(layers "B.Cu" "B.Mask" "B.Paste")
			(net "FPGA_TCK")
		)
		(pad "2" smd rect
			(at -0.5334 0 90)
			(size 0.7112 0.6096)
			(layers "B.Cu" "B.Mask" "B.Paste")
			(net "SG")
		)
		(zone
			(layer "B.Cu")
			(hatch none 0.5)
			(connect_pads
				(clearance 0)
			)
			(min_thickness 0.25)
			(keepout
				(tracks allowed)
				(vias not_allowed)
				(pads allowed)
				(copperpour not_allowed)
				(footprints allowed)
			)
			(placement
				(enabled no)
				(sheetname "")
			)
			(fill
				(thermal_gap 0.5)
				(thermal_bridge_width 0.5)
				(island_removal_mode 0)
			)
			(polygon
				(pts
					(xy 138.1887 -67.4497) (xy 138.7983 -67.4497) (xy 138.7983 -67.6021) (xy 138.1887 -67.6021)
				)
			)
		)
		(zone
			(layer "B.Cu")
			(hatch none 0.5)
			(connect_pads
				(clearance 0)
			)
			(min_thickness 0.25)
			(keepout
				(tracks not_allowed)
				(vias allowed)
				(pads allowed)
				(copperpour not_allowed)
				(footprints allowed)
			)
			(placement
				(enabled no)
				(sheetname "")
			)
			(fill
				(thermal_gap 0.5)
				(thermal_bridge_width 0.5)
				(island_removal_mode 0)
			)
			(polygon
				(pts
					(xy 138.1887 -67.4497) (xy 138.7983 -67.4497) (xy 138.7983 -67.6021) (xy 138.1887 -67.6021)
				)
			)
		)
	)
)
